(kicad_pcb
	(version 20260206)
	(generator "pcbnew")
	(generator_version "10.0")
	(general
		(thickness 1.6)
		(legacy_teardrops no)
	)
	(paper "A4")
	(title_block
		(title "01162023_DA0F0TEBIF0_F0T_Expander_BD_F_brd_V02_OCP.brd")
		(comment 1 "Grand Teton / footprint 2274 of 9728 (J22), pads 110-179 of 179")
	)
	(layers
		(0 "F.Cu" signal "TOP")
		(4 "In1.Cu" signal "GND")
		(6 "In2.Cu" signal "VCC")
		(8 "In3.Cu" signal "VCC1")
		(10 "In4.Cu" signal "GND1")
		(12 "In5.Cu" signal "IN1")
		(14 "In6.Cu" signal "GND2")
		(16 "In7.Cu" signal "IN2")
		(18 "In8.Cu" signal "GND3")
		(20 "In9.Cu" signal "IN3")
		(22 "In10.Cu" signal "GND4")
		(24 "In11.Cu" signal "IN4")
		(26 "In12.Cu" signal "GND5")
		(28 "In13.Cu" signal "IN5")
		(30 "In14.Cu" signal "GND6")
		(32 "In15.Cu" signal "IN6")
		(34 "In16.Cu" signal "GND7")
		(2 "B.Cu" signal "BOTTOM")
		(9 "F.Adhes" user "F.Adhesive")
		(11 "B.Adhes" user "B.Adhesive")
		(13 "F.Paste" user "Package Geometry/Pastemask Top")
		(15 "B.Paste" user "Package Geometry/Pastemask Bottom")
		(5 "F.SilkS" user "Ref Des/Silkscreen Top")
		(7 "B.SilkS" user "Ref Des/Silkscreen Bottom")
		(1 "F.Mask" user "Board Geometry/Soldermask Top")
		(3 "B.Mask" user "Board Geometry/Soldermask Bottom")
		(17 "Dwgs.User" user "User.Drawings")
		(19 "Cmts.User" user "User.Comments")
		(21 "Eco1.User" user "User.Eco1")
		(23 "Eco2.User" user "User.Eco2")
		(25 "Edge.Cuts" user "Board Geometry/Outline")
		(27 "Margin" user)
		(31 "F.CrtYd" user "Package Geometry/Place Bound Top")
		(29 "B.CrtYd" user "Package Geometry/Place Bound Bottom")
		(35 "F.Fab" user "Ref Des/Assembly Top")
		(33 "B.Fab" user "Ref Des/Assembly Bottom")
	)
	(footprint ""
		(layer "F.Cu")
		(at 163.41979 -127.700024)
		(property "Reference" "J22"
			(at -5.48132 34.685224 90)
			(unlocked yes)
			(layer "F.SilkS")
			(effects
				(font
					(size 0.7874 0.5842)
					(thickness 0.1524)
				)
				(justify left)
			)
		)
		(property "Value" ""
			(at 0 0 0)
			(layer "F.Fab")
			(effects
				(font
					(size 1.27 1.27)
				)
			)
		)
		(duplicate_pad_numbers_are_jumpers no)
		(pad "B38" smd rect
			(at -1.27762 7.14502 270)
			(size 0.3556 1.2192)
			(layers "F.Cu" "F.Mask" "F.Paste")
			(net "GND")
		)
		(pad "B39" smd rect
			(at -1.27762 7.744968 270)
			(size 0.3556 1.2192)
			(layers "F.Cu" "F.Mask" "F.Paste")
			(net "P5E_PEX1_STN1_TX_C_DN<24>")
		)
		(pad "B40" smd rect
			(at -1.27762 8.344916 270)
			(size 0.3556 1.2192)
			(layers "F.Cu" "F.Mask" "F.Paste")
			(net "P5E_PEX1_STN1_TX_C_DP<24>")
		)
		(pad "B41" smd rect
			(at -1.27762 8.945118 270)
			(size 0.3556 1.2192)
			(layers "F.Cu" "F.Mask" "F.Paste")
			(net "GND")
		)
		(pad "B42" smd rect
			(at -1.27762 9.545066 270)
			(size 0.3556 1.2192)
			(layers "F.Cu" "F.Mask" "F.Paste")
			(net "PRSNTB0_NIC2_N")
		)
		(pad "B43" smd rect
			(at -1.27762 14.454886 270)
			(size 0.3556 1.2192)
			(layers "F.Cu" "F.Mask" "F.Paste")
			(net "GND")
		)
		(pad "B44" smd rect
			(at -1.27762 15.055088 270)
			(size 0.3556 1.2192)
			(layers "F.Cu" "F.Mask" "F.Paste")
			(net "P5E_PEX1_STN1_TX_C_DP<23>")
		)
		(pad "B45" smd rect
			(at -1.27762 15.655036 270)
			(size 0.3556 1.2192)
			(layers "F.Cu" "F.Mask" "F.Paste")
			(net "P5E_PEX1_STN1_TX_C_DN<23>")
		)
		(pad "B46" smd rect
			(at -1.27762 16.254984 270)
			(size 0.3556 1.2192)
			(layers "F.Cu" "F.Mask" "F.Paste")
			(net "GND")
		)
		(pad "B47" smd rect
			(at -1.27762 16.854932 270)
			(size 0.3556 1.2192)
			(layers "F.Cu" "F.Mask" "F.Paste")
			(net "P5E_PEX1_STN1_TX_C_DN<22>")
		)
		(pad "B48" smd rect
			(at -1.27762 17.45488 270)
			(size 0.3556 1.2192)
			(layers "F.Cu" "F.Mask" "F.Paste")
			(net "P5E_PEX1_STN1_TX_C_DP<22>")
		)
		(pad "B49" smd rect
			(at -1.27762 18.055082 270)
			(size 0.3556 1.2192)
			(layers "F.Cu" "F.Mask" "F.Paste")
			(net "GND")
		)
		(pad "B50" smd rect
			(at -1.27762 18.65503 270)
			(size 0.3556 1.2192)
			(layers "F.Cu" "F.Mask" "F.Paste")
			(net "P5E_PEX1_STN1_TX_C_DP<21>")
		)
		(pad "B51" smd rect
			(at -1.27762 19.254978 270)
			(size 0.3556 1.2192)
			(layers "F.Cu" "F.Mask" "F.Paste")
			(net "P5E_PEX1_STN1_TX_C_DN<21>")
		)
		(pad "B52" smd rect
			(at -1.27762 19.854926 270)
			(size 0.3556 1.2192)
			(layers "F.Cu" "F.Mask" "F.Paste")
			(net "GND")
		)
		(pad "B53" smd rect
			(at -1.27762 20.455128 270)
			(size 0.3556 1.2192)
			(layers "F.Cu" "F.Mask" "F.Paste")
			(net "P5E_PEX1_STN1_TX_C_DN<20>")
		)
		(pad "B54" smd rect
			(at -1.27762 21.055076 270)
			(size 0.3556 1.2192)
			(layers "F.Cu" "F.Mask" "F.Paste")
			(net "P5E_PEX1_STN1_TX_C_DP<20>")
		)
		(pad "B55" smd rect
			(at -1.27762 21.655024 270)
			(size 0.3556 1.2192)
			(layers "F.Cu" "F.Mask" "F.Paste")
			(net "GND")
		)
		(pad "B56" smd rect
			(at -1.27762 22.254972 270)
			(size 0.3556 1.2192)
			(layers "F.Cu" "F.Mask" "F.Paste")
			(net "P5E_PEX1_STN1_TX_C_DP<19>")
		)
		(pad "B57" smd rect
			(at -1.27762 22.85492 270)
			(size 0.3556 1.2192)
			(layers "F.Cu" "F.Mask" "F.Paste")
			(net "P5E_PEX1_STN1_TX_C_DN<19>")
		)
		(pad "B58" smd rect
			(at -1.27762 23.455122 270)
			(size 0.3556 1.2192)
			(layers "F.Cu" "F.Mask" "F.Paste")
			(net "GND")
		)
		(pad "B59" smd rect
			(at -1.27762 24.05507 270)
			(size 0.3556 1.2192)
			(layers "F.Cu" "F.Mask" "F.Paste")
			(net "P5E_PEX1_STN1_TX_C_DN<18>")
		)
		(pad "B60" smd rect
			(at -1.27762 24.655018 270)
			(size 0.3556 1.2192)
			(layers "F.Cu" "F.Mask" "F.Paste")
			(net "P5E_PEX1_STN1_TX_C_DP<18>")
		)
		(pad "B61" smd rect
			(at -1.27762 25.254966 270)
			(size 0.3556 1.2192)
			(layers "F.Cu" "F.Mask" "F.Paste")
			(net "GND")
		)
		(pad "B62" smd rect
			(at -1.27762 25.854914 270)
			(size 0.3556 1.2192)
			(layers "F.Cu" "F.Mask" "F.Paste")
			(net "P5E_PEX1_STN1_TX_C_DP<17>")
		)
		(pad "B63" smd rect
			(at -1.27762 26.455116 270)
			(size 0.3556 1.2192)
			(layers "F.Cu" "F.Mask" "F.Paste")
			(net "P5E_PEX1_STN1_TX_C_DN<17>")
		)
		(pad "B64" smd rect
			(at -1.27762 27.055064 270)
			(size 0.3556 1.2192)
			(layers "F.Cu" "F.Mask" "F.Paste")
			(net "GND")
		)
		(pad "B65" smd rect
			(at -1.27762 27.655012 270)
			(size 0.3556 1.2192)
			(layers "F.Cu" "F.Mask" "F.Paste")
			(net "P5E_PEX1_STN1_TX_C_DN<16>")
		)
		(pad "B66" smd rect
			(at -1.27762 28.25496 270)
			(size 0.3556 1.2192)
			(layers "F.Cu" "F.Mask" "F.Paste")
			(net "P5E_PEX1_STN1_TX_C_DP<16>")
		)
		(pad "B67" smd rect
			(at -1.27762 28.854908 270)
			(size 0.3556 1.2192)
			(layers "F.Cu" "F.Mask" "F.Paste")
			(net "GND")
		)
		(pad "B68" smd rect
			(at -1.27762 29.45511 270)
			(size 0.3556 1.2192)
			(layers "F.Cu" "F.Mask" "F.Paste")
			(net "Net_2607")
		)
		(pad "B69" smd rect
			(at -1.27762 30.055058 270)
			(size 0.3556 1.2192)
			(layers "F.Cu" "F.Mask" "F.Paste")
			(net "Net_2608")
		)
		(pad "B70" smd rect
			(at -1.27762 30.655006 270)
			(size 0.3556 1.2192)
			(layers "F.Cu" "F.Mask" "F.Paste")
			(net "PRSNTB3_NIC2_N")
		)
		(pad "G1" thru_hole oval
			(at 1.022604 -34.034984 270)
			(size 1.6256 3.4798)
			(drill oval 1.1176 2.4638)
			(layers "*.Cu" "*.Mask")
			(remove_unused_layers no)
			(net "GND")
			(clearance 0.127)
			(thermal_gap 0.127)
		)
		(pad "G2" thru_hole oval
			(at 1.022604 -20.625054 270)
			(size 1.6256 3.4798)
			(drill oval 1.1176 2.4638)
			(layers "*.Cu" "*.Mask")
			(remove_unused_layers no)
			(net "GND")
			(clearance 0.127)
			(thermal_gap 0.127)
		)
		(pad "G3" thru_hole oval
			(at 1.022604 -0.255016 270)
			(size 1.6256 3.4798)
			(drill oval 1.1176 2.4638)
			(layers "*.Cu" "*.Mask")
			(remove_unused_layers no)
			(net "GND")
			(clearance 0.127)
			(thermal_gap 0.127)
		)
		(pad "G4" thru_hole oval
			(at 1.022604 12.005056 270)
			(size 1.6256 3.4798)
			(drill oval 1.1176 2.4638)
			(layers "*.Cu" "*.Mask")
			(remove_unused_layers no)
			(net "GND")
			(clearance 0.127)
			(thermal_gap 0.127)
		)
		(pad "G5" thru_hole oval
			(at 1.022604 34.034984 270)
			(size 1.5748 3.4798)
			(drill oval 1.1176 2.4638)
			(layers "*.Cu" "*.Mask")
			(remove_unused_layers no)
			(net "GND")
			(clearance 0.1524)
			(thermal_gap 0.1524)
		)
		(pad "G6" thru_hole circle
			(at -3.16738 -20.625054)
			(size 1.6256 1.6256)
			(drill 1.1176)
			(layers "*.Cu" "*.Mask")
			(remove_unused_layers no)
			(net "GND")
			(clearance 0)
		)
		(pad "G7" thru_hole circle
			(at -3.16738 12.005056)
			(size 1.6256 1.6256)
			(drill 1.1176)
			(layers "*.Cu" "*.Mask")
			(remove_unused_layers no)
			(net "GND")
			(clearance 0)
		)
		(pad "G8" thru_hole circle
			(at 4.20243 -20.625054)
			(size 1.6256 1.6256)
			(drill 1.1176)
			(layers "*.Cu" "*.Mask")
			(remove_unused_layers no)
			(net "GND")
			(clearance 0)
		)
		(pad "G9" thru_hole circle
			(at 4.20243 12.005056)
			(size 1.6256 1.6256)
			(drill 1.1176)
			(layers "*.Cu" "*.Mask")
			(remove_unused_layers no)
			(net "GND")
			(clearance 0)
		)
		(pad "OA1" smd rect
			(at 3.322574 -30.660086 270)
			(size 0.3556 1.2192)
			(layers "F.Cu" "F.Mask" "F.Paste")
			(net "RST_NIC2_PERST2_R_N")
		)
		(pad "OA2" smd rect
			(at 3.322574 -30.059884 270)
			(size 0.3556 1.2192)
			(layers "F.Cu" "F.Mask" "F.Paste")
			(net "RST_NIC2_PERST3_R_N")
		)
		(pad "OA3" smd rect
			(at 3.322574 -29.459936 270)
			(size 0.3556 1.2192)
			(layers "F.Cu" "F.Mask" "F.Paste")
			(net "Net_2611")
		)
		(pad "OA4" smd rect
			(at 3.322574 -28.859988 270)
			(size 0.3556 1.2192)
			(layers "F.Cu" "F.Mask" "F.Paste")
			(net "NIC2_RBT_ARB_IN")
		)
		(pad "OA5" smd rect
			(at 3.322574 -28.26004 270)
			(size 0.3556 1.2192)
			(layers "F.Cu" "F.Mask" "F.Paste")
			(net "NIC2_RBT_ARB_OUT")
		)
		(pad "OA6" smd rect
			(at 3.322574 -27.660092 270)
			(size 0.3556 1.2192)
			(layers "F.Cu" "F.Mask" "F.Paste")
			(net "NIC2_SLOT_ID1")
		)
		(pad "OA7" smd rect
			(at 3.322574 -27.05989 270)
			(size 0.3556 1.2192)
			(layers "F.Cu" "F.Mask" "F.Paste")
			(net "NCSI_NIC2_TX_EN")
		)
		(pad "OA8" smd rect
			(at 3.322574 -26.459942 270)
			(size 0.3556 1.2192)
			(layers "F.Cu" "F.Mask" "F.Paste")
			(net "NCSI_NIC2_TXD1")
		)
		(pad "OA9" smd rect
			(at 3.322574 -25.859994 270)
			(size 0.3556 1.2192)
			(layers "F.Cu" "F.Mask" "F.Paste")
			(net "NCSI_NIC2_TXD0")
		)
		(pad "OA10" smd rect
			(at 3.322574 -25.260046 270)
			(size 0.3556 1.2192)
			(layers "F.Cu" "F.Mask" "F.Paste")
			(net "GND")
		)
		(pad "OA11" smd rect
			(at 3.322574 -24.660098 270)
			(size 0.3556 1.2192)
			(layers "F.Cu" "F.Mask" "F.Paste")
			(net "Net_2603")
		)
		(pad "OA12" smd rect
			(at 3.322574 -24.059896 270)
			(size 0.3556 1.2192)
			(layers "F.Cu" "F.Mask" "F.Paste")
			(net "Net_2606")
		)
		(pad "OA13" smd rect
			(at 3.322574 -23.459948 270)
			(size 0.3556 1.2192)
			(layers "F.Cu" "F.Mask" "F.Paste")
			(net "GND")
		)
		(pad "OA14" smd rect
			(at 3.322574 -22.86 270)
			(size 0.3556 1.2192)
			(layers "F.Cu" "F.Mask" "F.Paste")
			(net "CLK_50M_NIC2_RBT_REF")
		)
		(pad "OB1" smd rect
			(at -1.27762 -30.660086 270)
			(size 0.3556 1.2192)
			(layers "F.Cu" "F.Mask" "F.Paste")
			(net "PWRGD_NIC2_PWR_GOOD")
		)
		(pad "OB2" smd rect
			(at -1.27762 -30.059884 270)
			(size 0.3556 1.2192)
			(layers "F.Cu" "F.Mask" "F.Paste")
			(net "NIC2_MAIN_PWR_EN_R")
		)
		(pad "OB3" smd rect
			(at -1.27762 -29.459936 270)
			(size 0.3556 1.2192)
			(layers "F.Cu" "F.Mask" "F.Paste")
			(net "NIC2_LD_N")
		)
		(pad "OB4" smd rect
			(at -1.27762 -28.859988 270)
			(size 0.3556 1.2192)
			(layers "F.Cu" "F.Mask" "F.Paste")
			(net "NIC2_DATA_IN")
		)
		(pad "OB5" smd rect
			(at -1.27762 -28.26004 270)
			(size 0.3556 1.2192)
			(layers "F.Cu" "F.Mask" "F.Paste")
			(net "NIC2_DATA_OUT")
		)
		(pad "OB6" smd rect
			(at -1.27762 -27.660092 270)
			(size 0.3556 1.2192)
			(layers "F.Cu" "F.Mask" "F.Paste")
			(net "NIC2_CLK")
		)
		(pad "OB7" smd rect
			(at -1.27762 -27.05989 270)
			(size 0.3556 1.2192)
			(layers "F.Cu" "F.Mask" "F.Paste")
			(net "NIC2_SLOT_ID0")
		)
		(pad "OB8" smd rect
			(at -1.27762 -26.459942 270)
			(size 0.3556 1.2192)
			(layers "F.Cu" "F.Mask" "F.Paste")
			(net "NCSI_NIC2_RXD1")
		)
		(pad "OB9" smd rect
			(at -1.27762 -25.859994 270)
			(size 0.3556 1.2192)
			(layers "F.Cu" "F.Mask" "F.Paste")
			(net "NCSI_NIC2_RXD0")
		)
		(pad "OB10" smd rect
			(at -1.27762 -25.260046 270)
			(size 0.3556 1.2192)
			(layers "F.Cu" "F.Mask" "F.Paste")
			(net "GND")
		)
		(pad "OB11" smd rect
			(at -1.27762 -24.660098 270)
			(size 0.3556 1.2192)
			(layers "F.Cu" "F.Mask" "F.Paste")
			(net "Net_2602")
		)
		(pad "OB12" smd rect
			(at -1.27762 -24.059896 270)
			(size 0.3556 1.2192)
			(layers "F.Cu" "F.Mask" "F.Paste")
			(net "Net_2605")
		)
		(pad "OB13" smd rect
			(at -1.27762 -23.459948 270)
			(size 0.3556 1.2192)
			(layers "F.Cu" "F.Mask" "F.Paste")
			(net "GND")
		)
		(pad "OB14" smd rect
			(at -1.27762 -22.86 270)
			(size 0.3556 1.2192)
			(layers "F.Cu" "F.Mask" "F.Paste")
			(net "NCSI_NIC2_CRS_DV")
		)
	)
)
